# T6G (Grand Teton) — schematic netlist excerpt (pin names and nets, part order shuffled) for the footprints in the layout excerpt that follows; sources: Cadence DE-HDL packaged netlist, KiCad conversion of 04192023_DAF0TMB3IC0_F0TG_MB_C_brd_V02_OCP.brd

J24  SCONN288_DDR506112002KQ  IO  pkg DDR288S_1-1VXC  page 98
  VIN_BULK0  = P12V_MEM_CPU1
  RFU0  = NC
  VIN_MGMT  = P3V3_AUX
  HSCL  = I3C_SPD_DDRA_CPU1_SCL
  HSDA  = I3C_SPD_DDRA_CPU1_SDA
  VSS0  = GND
  DQ0_A  = M_A_CPU1_SA_DQ<0>
  VSS1  = GND
  DQ1_A  = M_A_CPU1_SA_DQ<1>
  VSS2  = GND
  DQS0_A_T  = M_A_CPU1_SA_DQS_DP<0>
  DQS0_A_C  = M_A_CPU1_SA_DQS_DN<0>
  VSS3  = GND
  DQ4_A  = M_A_CPU1_SA_DQ<4>
  VSS4  = GND
  DQ5_A  = M_A_CPU1_SA_DQ<5>
  VSS5  = GND
  DQ8_A  = M_A_CPU1_SA_DQ<8>
  VSS6  = GND
  DQ9_A  = M_A_CPU1_SA_DQ<9>
  VSS7  = GND
  DQS1_A_T  = M_A_CPU1_SA_DQS_DP<1>
  DQS1_A_C  = M_A_CPU1_SA_DQS_DN<1>
  VSS8  = GND
  DQ12_A  = M_A_CPU1_SA_DQ<12>
  VSS9  = GND
  DQ13_A  = M_A_CPU1_SA_DQ<13>
  VSS10  = GND
  DQ16_A  = M_A_CPU1_SA_DQ<16>
  VSS11  = GND
  DQ17_A  = M_A_CPU1_SA_DQ<17>
  VSS12  = GND
  DQS2_A_T  = M_A_CPU1_SA_DQS_DP<2>
  DQS2_A_C  = M_A_CPU1_SA_DQS_DN<2>
  VSS13  = GND
  DQ20_A  = M_A_CPU1_SA_DQ<20>
  VSS14  = GND
  DQ21_A  = M_A_CPU1_SA_DQ<21>
  VSS15  = GND
  DQ24_A  = M_A_CPU1_SA_DQ<24>
  VSS16  = GND
  DQ25_A  = M_A_CPU1_SA_DQ<25>
  VSS17  = GND
  DQS3_A_T  = M_A_CPU1_SA_DQS_DP<3>
  DQS3_A_C  = M_A_CPU1_SA_DQS_DN<3>
  VSS18  = GND
  DQ28_A  = M_A_CPU1_SA_DQ<28>
  VSS19  = GND
  DQ29_A  = M_A_CPU1_SA_DQ<29>
  VSS20  = GND
  CB0_A  = M_A_CPU1_SA_CB<0>
  VSS21  = GND
  CB1_A  = M_A_CPU1_SA_CB<1>
  VSS22  = GND
  DQS4_A_T  = M_A_CPU1_SA_DQS_DP<4>
  DQS4_A_C  = M_A_CPU1_SA_DQS_DN<4>
  VSS23  = GND
  CB4_A  = M_A_CPU1_SA_CB<4>
  VSS24  = GND
  CB5_A  = M_A_CPU1_SA_CB<5>
  VSS25  = GND
  ALERT_N  = M_A_CPU1_ALERT_N
  VSS26  = GND
  CS0_A_N  = M_A_CPU1_SA_CS_N<0>
  VSS27  = GND
  CA0_A  = M_A_CPU1_SA_CA<0>
  VSS28  = GND
  CA2_A  = M_A_CPU1_SA_CA<2>
  VSS29  = GND
  CA4_A  = M_A_CPU1_SA_CA<4>
  VSS30  = GND
  CA6_A  = M_A_CPU1_SA_CA<6>
  VSS31  = GND
  PAR_A  = M_A_CPU1_SA_PAR
  VSS32  = GND
  CA0_B  = M_A_CPU1_SB_CA<0>
  VSS33  = GND
  CA2_B  = M_A_CPU1_SB_CA<2>
  VSS34  = GND
  CA4_B  = M_A_CPU1_SB_CA<4>
  VSS35  = GND
  CA6_B  = M_A_CPU1_SB_CA<6>
  VSS36  = GND
  CS0_B_N  = M_A_CPU1_SB_CS_N<0>
  VSS37  = GND
  \lbd||rsp_a_n\  = M_A_CPU1_SA_RSP<0>
  \lbs||rsp_b_n\  = M_A_CPU1_SB_RSP<0>
  VSS38  = GND
  CB4_B  = M_A_CPU1_SB_CB<4>
  VSS39  = GND
  CB5_B  = M_A_CPU1_SB_CB<5>
  VSS40  = GND
  \dqs9_b_t||tdqs9_b_t||dbi4_b_n\  = M_A_CPU1_SB_DQS_DP<9>
  \dqs9_b_c||tdqs9_b_c\  = M_A_CPU1_SB_DQS_DN<9>
  VSS41  = GND
  CB0_B  = M_A_CPU1_SB_CB<0>
  VSS42  = GND
  CB1_B  = M_A_CPU1_SB_CB<1>
  VSS43  = GND
  DQ0_B  = M_A_CPU1_SB_DQ<0>
  VSS44  = GND
  DQ1_B  = M_A_CPU1_SB_DQ<1>
  VSS45  = GND
  DQS0_B_T  = M_A_CPU1_SB_DQS_DP<0>
  DQS0_B_C  = M_A_CPU1_SB_DQS_DN<0>
  VSS46  = GND
  DQ4_B  = M_A_CPU1_SB_DQ<4>
  VSS47  = GND
  DQ5_B  = M_A_CPU1_SB_DQ<5>
  VSS48  = GND
  DQ8_B  = M_A_CPU1_SB_DQ<8>
  VSS49  = GND
  DQ9_B  = M_A_CPU1_SB_DQ<9>
  VSS50  = GND
  DQS1_B_T  = M_A_CPU1_SB_DQS_DP<1>
  DQS1_B_C  = M_A_CPU1_SB_DQS_DN<1>
  VSS51  = GND
  DQ12_B  = M_A_CPU1_SB_DQ<12>
  VSS52  = GND
  DQ13_B  = M_A_CPU1_SB_DQ<13>
  VSS53  = GND
  DQ16_B  = M_A_CPU1_SB_DQ<16>
  VSS54  = GND
  DQ17_B  = M_A_CPU1_SB_DQ<17>
  VSS55  = GND
  DQS2_B_T  = M_A_CPU1_SB_DQS_DP<2>
  DQS2_B_C  = M_A_CPU1_SB_DQS_DN<2>
  VSS56  = GND
  DQ20_B  = M_A_CPU1_SB_DQ<20>
  VSS57  = GND
  DQ21_B  = M_A_CPU1_SB_DQ<21>
  VSS58  = GND
  DQ24_B  = M_A_CPU1_SB_DQ<24>
  VSS59  = GND
  DQ25_B  = M_A_CPU1_SB_DQ<25>
  VSS60  = GND
  DQS3_B_T  = M_A_CPU1_SB_DQS_DP<3>
  DQS3_B_C  = M_A_CPU1_SB_DQS_DN<3>
  VSS61  = GND
  DQ28_B  = M_A_CPU1_SB_DQ<28>
  VSS62  = GND
  DQ29_B  = M_A_CPU1_SB_DQ<29>
  VSS63  = GND
  RFU1  = NC
  VIN_BULK1  = P12V_MEM_CPU1
  VIN_BULK2  = P12V_MEM_CPU1
  \pwr_good||fail_n\  = PWRGD_CHA_CPU1_DIMM0
  HAS  = PD_CHA_CPU1_DIMM0_SAA
  RFU2  = NC
  RFU3  = NC
  VSS64  = GND
  DQ2_A  = M_A_CPU1_SA_DQ<2>
  VSS65  = GND
  DQ3_A  = M_A_CPU1_SA_DQ<3>
  VSS66  = GND
  \dqs5_a_c||tdqs5_a_c||dqs5_a_t||tdqs5_a_t\  = M_A_CPU1_SA_DQS_DN<5>
  \dqs5_a_t||tdqs5_a_t\  = M_A_CPU1_SA_DQS_DP<5>
  VSS67  = GND
  DQ6_A  = M_A_CPU1_SA_DQ<6>
  VSS68  = GND
  DQ7_A  = M_A_CPU1_SA_DQ<7>
  VSS69  = GND
  DQ10_A  = M_A_CPU1_SA_DQ<10>
  VSS70  = GND
  DQ11_A  = M_A_CPU1_SA_DQ<11>
  VSS71  = GND
  \dqs6_a_c||tdqs6_a_c||dqs6_a_t||tdqs6_a_t\  = M_A_CPU1_SA_DQS_DN<6>
  \dqs6_a_t||tdqs6_a_t\  = M_A_CPU1_SA_DQS_DP<6>
  VSS72  = GND
  DQ14_A  = M_A_CPU1_SA_DQ<14>
  VSS73  = GND
  DQ15_A  = M_A_CPU1_SA_DQ<15>
  VSS74  = GND
  DQ18_A  = M_A_CPU1_SA_DQ<18>
  VSS75  = GND
  DQ19_A  = M_A_CPU1_SA_DQ<19>
  VSS76  = GND
  \dqs7_a_c||tdqs7_a_c\  = M_A_CPU1_SA_DQS_DN<7>
  \dqs7_a_t||tdqs7_a_t\  = M_A_CPU1_SA_DQS_DP<7>
  VSS77  = GND
  DQ22_A  = M_A_CPU1_SA_DQ<22>
  VSS78  = GND
  DQ23_A  = M_A_CPU1_SA_DQ<23>
  VSS79  = GND
  DQ26_A  = M_A_CPU1_SA_DQ<26>
  VSS80  = GND
  DQ27_A  = M_A_CPU1_SA_DQ<27>
  VSS81  = GND
  \dqs8_a_c||tdqs8_a_c\  = M_A_CPU1_SA_DQS_DN<8>
  \dqs8_a_t||tdqs8_a_t\  = M_A_CPU1_SA_DQS_DP<8>
  VSS82  = GND
  DQ30_A  = M_A_CPU1_SA_DQ<30>
  VSS83  = GND
  DQ31_A  = M_A_CPU1_SA_DQ<31>
  VSS84  = GND
  CB2_A  = M_A_CPU1_SA_CB<2>
  VSS85  = GND
  CB3_A  = M_A_CPU1_SA_CB<3>
  VSS86  = GND
  \dqs9_a_c||tdqs9_a_c\  = M_A_CPU1_SA_DQS_DN<9>
  \dqs9_a_t||tdqs9_a_t\  = M_A_CPU1_SA_DQS_DP<9>
  VSS87  = GND
  CB6_A  = M_A_CPU1_SA_CB<6>
  VSS88  = GND
  CB7_A  = M_A_CPU1_SA_CB<7>
  VSS89  = GND
  RESET_N  = M_A_CPU1_RESET_N
  VSS90  = GND
  CS1_A_N  = M_A_CPU1_SA_CS_N<1>
  VSS91  = GND
  CA1_A  = M_A_CPU1_SA_CA<1>
  VSS92  = GND
  CA3_A  = M_A_CPU1_SA_CA<3>
  VSS93  = GND
  CA5_A  = M_A_CPU1_SA_CA<5>
  VSS94  = GND
  CK_T  = M_A_CPU1_CLK_DP<0>
  CK_C  = M_A_CPU1_CLK_DN<0>
  VSS95  = GND
  RFU4  = NC
  CA1_B  = M_A_CPU1_SB_CA<1>
  VSS96  = GND
  CA3_B  = M_A_CPU1_SB_CA<3>
  VSS97  = GND
  CA5_B  = M_A_CPU1_SB_CA<5>
  VSS98  = GND
  PAR_B  = M_A_CPU1_SB_PAR
  VSS99  = GND
  CS1_B_N  = M_A_CPU1_SB_CS_N<1>
  VSS100  = GND
  RFU5  = NC
  RFU6  = NC
  VSS101  = GND
  CB6_B  = M_A_CPU1_SB_CB<6>
  VSS102  = GND
  CB7_B  = M_A_CPU1_SB_CB<7>
  VSS103  = GND
  DQS4_B_C  = M_A_CPU1_SB_DQS_DN<4>
  DQS4_B_T  = M_A_CPU1_SB_DQS_DP<4>
  VSS104  = GND
  CB2_B  = M_A_CPU1_SB_CB<2>
  VSS105  = GND
  CB3_B  = M_A_CPU1_SB_CB<3>
  VSS106  = GND
  DQ2_B  = M_A_CPU1_SB_DQ<2>
  VSS107  = GND
  DQ3_B  = M_A_CPU1_SB_DQ<3>
  VSS108  = GND
  \dqs5_b_c||tdqs5_b_c\  = M_A_CPU1_SB_DQS_DN<5>
  \dqs5_b_t||tdqs5_b_t\  = M_A_CPU1_SB_DQS_DP<5>
  VSS109  = GND
  DQ6_B  = M_A_CPU1_SB_DQ<6>
  VSS110  = GND
  DQ7_B  = M_A_CPU1_SB_DQ<7>
  VSS111  = GND
  DQ10_B  = M_A_CPU1_SB_DQ<10>
  VSS112  = GND
  DQ11_B  = M_A_CPU1_SB_DQ<11>
  VSS113  = GND
  \dqs6_b_c||tdqs6_b_c\  = M_A_CPU1_SB_DQS_DN<6>
  \dqs6_b_t||tdqs6_b_t\  = M_A_CPU1_SB_DQS_DP<6>
  VSS114  = GND
  DQ14_B  = M_A_CPU1_SB_DQ<14>
  VSS115  = GND
  DQ15_B  = M_A_CPU1_SB_DQ<15>
  VSS116  = GND
  DQ18_B  = M_A_CPU1_SB_DQ<18>
  VSS117  = GND
  DQ19_B  = M_A_CPU1_SB_DQ<19>
  VSS118  = GND
  \dqs7_b_c||tdqs7_b_c\  = M_A_CPU1_SB_DQS_DN<7>
  \dqs7_b_t||tdqs7_b_t\  = M_A_CPU1_SB_DQS_DP<7>
  VSS119  = GND
  DQ22_B  = M_A_CPU1_SB_DQ<22>
  VSS120  = GND
  DQ23_B  = M_A_CPU1_SB_DQ<23>
  VSS121  = GND
  DQ26_B  = M_A_CPU1_SB_DQ<26>
  VSS122  = GND
  DQ27_B  = M_A_CPU1_SB_DQ<27>
  VSS123  = GND
  \dqs8_b_c||tdqs8_b_c\  = M_A_CPU1_SB_DQS_DN<8>
  \dqs8_b_t||tdqs8_b_t\  = M_A_CPU1_SB_DQS_DP<8>
  VSS124  = GND
  DQ30_B  = M_A_CPU1_SB_DQ<30>
  VSS125  = GND
  DQ31_B  = M_A_CPU1_SB_DQ<31>
  VSS126  = GND
  G1  = GND
  G2  = GND
  G3  = GND

(kicad_pcb
	(version 20260206)
	(generator "pcbnew")
	(generator_version "10.0")
	(general
		(thickness 1.6)
		(legacy_teardrops no)
	)
	(paper "A4")
	(title_block
		(title "04192023_DAF0TMB3IC0_F0TG_MB_C_brd_V02_OCP.brd")
		(comment 1 "Grand Teton / footprint 2100 of 8354 (J24), pads 231-276 of 291")
	)
	(layers
		(0 "F.Cu" signal "TOP")
		(4 "In1.Cu" signal "GND")
		(6 "In2.Cu" signal "IN1")
		(8 "In3.Cu" signal "GND1")
		(10 "In4.Cu" signal "IN2")
		(12 "In5.Cu" signal "GND2")
		(14 "In6.Cu" signal "IN3")
		(16 "In7.Cu" signal "GND3")
		(18 "In8.Cu" signal "VCC")
		(20 "In9.Cu" signal "VCC1")
		(22 "In10.Cu" signal "GND4")
		(24 "In11.Cu" signal "IN4")
		(26 "In12.Cu" signal "GND5")
		(28 "In13.Cu" signal "IN5")
		(30 "In14.Cu" signal "GND6")
		(32 "In15.Cu" signal "IN6")
		(34 "In16.Cu" signal "GND7")
		(2 "B.Cu" signal "BOTTOM")
		(9 "F.Adhes" user "F.Adhesive")
		(11 "B.Adhes" user "B.Adhesive")
		(13 "F.Paste" user "Package Geometry/Pastemask Top")
		(15 "B.Paste" user "Package Geometry/Pastemask Bottom")
		(5 "F.SilkS" user "Ref Des/Silkscreen Top")
		(7 "B.SilkS" user "Ref Des/Silkscreen Bottom")
		(1 "F.Mask" user "Board Geometry/Soldermask Top")
		(3 "B.Mask" user "Board Geometry/Soldermask Bottom")
		(17 "Dwgs.User" user "User.Drawings")
		(19 "Cmts.User" user "User.Comments")
		(21 "Eco1.User" user "User.Eco1")
		(23 "Eco2.User" user "User.Eco2")
		(25 "Edge.Cuts" user "Board Geometry/Outline")
		(27 "Margin" user)
		(31 "F.CrtYd" user "Package Geometry/Place Bound Top")
		(29 "B.CrtYd" user "Package Geometry/Place Bound Bottom")
		(35 "F.Fab" user "Ref Des/Assembly Top")
		(33 "B.Fab" user "Ref Des/Assembly Bottom")
	)
	(footprint ""
		(layer "F.Cu")
		(at 57.378092 -255.560322 180)
		(property "Reference" "J24"
			(at 1.914906 -84.58708 0)
			(unlocked yes)
			(layer "F.SilkS")
			(effects
				(font
					(size 0.7874 0.5842)
					(thickness 0.1524)
				)
			)
		)
		(property "Value" ""
			(at 0 0 180)
			(layer "F.Fab")
			(effects
				(font
					(size 1.27 1.27)
				)
			)
		)
		(duplicate_pad_numbers_are_jumpers no)
		(pad "231" smd rect
			(at 2.050034 14.875002 90)
			(size 0.519938 1.4986)
			(layers "F.Cu" "F.Mask" "F.Paste")
			(net "Net_2261")
		)
		(pad "232" smd rect
			(at 2.050034 15.724886 90)
			(size 0.519938 1.4986)
			(layers "F.Cu" "F.Mask" "F.Paste")
			(net "Net_2262")
		)
		(pad "233" smd rect
			(at 2.050034 16.575024 90)
			(size 0.519938 1.4986)
			(layers "F.Cu" "F.Mask" "F.Paste")
			(net "GND")
		)
		(pad "234" smd rect
			(at 2.050034 17.424908 90)
			(size 0.519938 1.4986)
			(layers "F.Cu" "F.Mask" "F.Paste")
			(net "M_A_CPU1_SB_CB<6>")
		)
		(pad "235" smd rect
			(at 2.050034 18.275046 90)
			(size 0.519938 1.4986)
			(layers "F.Cu" "F.Mask" "F.Paste")
			(net "GND")
		)
		(pad "236" smd rect
			(at 2.050034 19.12493 90)
			(size 0.519938 1.4986)
			(layers "F.Cu" "F.Mask" "F.Paste")
			(net "M_A_CPU1_SB_CB<7>")
		)
		(pad "237" smd rect
			(at 2.050034 19.975068 90)
			(size 0.519938 1.4986)
			(layers "F.Cu" "F.Mask" "F.Paste")
			(net "GND")
		)
		(pad "238" smd rect
			(at 2.050034 20.824952 90)
			(size 0.519938 1.4986)
			(layers "F.Cu" "F.Mask" "F.Paste")
			(net "M_A_CPU1_SB_DQS_DN<4>")
		)
		(pad "239" smd rect
			(at 2.050034 21.67509 90)
			(size 0.519938 1.4986)
			(layers "F.Cu" "F.Mask" "F.Paste")
			(net "M_A_CPU1_SB_DQS_DP<4>")
		)
		(pad "240" smd rect
			(at 2.050034 22.524974 90)
			(size 0.519938 1.4986)
			(layers "F.Cu" "F.Mask" "F.Paste")
			(net "GND")
		)
		(pad "241" smd rect
			(at 2.050034 23.375112 90)
			(size 0.519938 1.4986)
			(layers "F.Cu" "F.Mask" "F.Paste")
			(net "M_A_CPU1_SB_CB<2>")
		)
		(pad "242" smd rect
			(at 2.050034 24.224996 90)
			(size 0.519938 1.4986)
			(layers "F.Cu" "F.Mask" "F.Paste")
			(net "GND")
		)
		(pad "243" smd rect
			(at 2.050034 25.07488 90)
			(size 0.519938 1.4986)
			(layers "F.Cu" "F.Mask" "F.Paste")
			(net "M_A_CPU1_SB_CB<3>")
		)
		(pad "244" smd rect
			(at 2.050034 25.925018 90)
			(size 0.519938 1.4986)
			(layers "F.Cu" "F.Mask" "F.Paste")
			(net "GND")
		)
		(pad "245" smd rect
			(at 2.050034 26.774902 90)
			(size 0.519938 1.4986)
			(layers "F.Cu" "F.Mask" "F.Paste")
			(net "M_A_CPU1_SB_DQ<2>")
		)
		(pad "246" smd rect
			(at 2.050034 27.62504 90)
			(size 0.519938 1.4986)
			(layers "F.Cu" "F.Mask" "F.Paste")
			(net "GND")
		)
		(pad "247" smd rect
			(at 2.050034 28.474924 90)
			(size 0.519938 1.4986)
			(layers "F.Cu" "F.Mask" "F.Paste")
			(net "M_A_CPU1_SB_DQ<3>")
		)
		(pad "248" smd rect
			(at 2.050034 29.325062 90)
			(size 0.519938 1.4986)
			(layers "F.Cu" "F.Mask" "F.Paste")
			(net "GND")
		)
		(pad "249" smd rect
			(at 2.050034 30.174946 90)
			(size 0.519938 1.4986)
			(layers "F.Cu" "F.Mask" "F.Paste")
			(net "M_A_CPU1_SB_DQS_DN<5>")
		)
		(pad "250" smd rect
			(at 2.050034 31.025084 90)
			(size 0.519938 1.4986)
			(layers "F.Cu" "F.Mask" "F.Paste")
			(net "M_A_CPU1_SB_DQS_DP<5>")
		)
		(pad "251" smd rect
			(at 2.050034 31.874968 90)
			(size 0.519938 1.4986)
			(layers "F.Cu" "F.Mask" "F.Paste")
			(net "GND")
		)
		(pad "252" smd rect
			(at 2.050034 32.725106 90)
			(size 0.519938 1.4986)
			(layers "F.Cu" "F.Mask" "F.Paste")
			(net "M_A_CPU1_SB_DQ<6>")
		)
		(pad "253" smd rect
			(at 2.050034 33.57499 90)
			(size 0.519938 1.4986)
			(layers "F.Cu" "F.Mask" "F.Paste")
			(net "GND")
		)
		(pad "254" smd rect
			(at 2.050034 34.425128 90)
			(size 0.519938 1.4986)
			(layers "F.Cu" "F.Mask" "F.Paste")
			(net "M_A_CPU1_SB_DQ<7>")
		)
		(pad "255" smd rect
			(at 2.050034 35.275012 90)
			(size 0.519938 1.4986)
			(layers "F.Cu" "F.Mask" "F.Paste")
			(net "GND")
		)
		(pad "256" smd rect
			(at 2.050034 36.124896 90)
			(size 0.519938 1.4986)
			(layers "F.Cu" "F.Mask" "F.Paste")
			(net "M_A_CPU1_SB_DQ<10>")
		)
		(pad "257" smd rect
			(at 2.050034 36.975034 90)
			(size 0.519938 1.4986)
			(layers "F.Cu" "F.Mask" "F.Paste")
			(net "GND")
		)
		(pad "258" smd rect
			(at 2.050034 37.824918 90)
			(size 0.519938 1.4986)
			(layers "F.Cu" "F.Mask" "F.Paste")
			(net "M_A_CPU1_SB_DQ<11>")
		)
		(pad "259" smd rect
			(at 2.050034 38.675056 90)
			(size 0.519938 1.4986)
			(layers "F.Cu" "F.Mask" "F.Paste")
			(net "GND")
		)
		(pad "260" smd rect
			(at 2.050034 39.52494 90)
			(size 0.519938 1.4986)
			(layers "F.Cu" "F.Mask" "F.Paste")
			(net "M_A_CPU1_SB_DQS_DN<6>")
		)
		(pad "261" smd rect
			(at 2.050034 40.375078 90)
			(size 0.519938 1.4986)
			(layers "F.Cu" "F.Mask" "F.Paste")
			(net "M_A_CPU1_SB_DQS_DP<6>")
		)
		(pad "262" smd rect
			(at 2.050034 41.224962 90)
			(size 0.519938 1.4986)
			(layers "F.Cu" "F.Mask" "F.Paste")
			(net "GND")
		)
		(pad "263" smd rect
			(at 2.050034 42.0751 90)
			(size 0.519938 1.4986)
			(layers "F.Cu" "F.Mask" "F.Paste")
			(net "M_A_CPU1_SB_DQ<14>")
		)
		(pad "264" smd rect
			(at 2.050034 42.924984 90)
			(size 0.519938 1.4986)
			(layers "F.Cu" "F.Mask" "F.Paste")
			(net "GND")
		)
		(pad "265" smd rect
			(at 2.050034 43.775122 90)
			(size 0.519938 1.4986)
			(layers "F.Cu" "F.Mask" "F.Paste")
			(net "M_A_CPU1_SB_DQ<15>")
		)
		(pad "266" smd rect
			(at 2.050034 44.625006 90)
			(size 0.519938 1.4986)
			(layers "F.Cu" "F.Mask" "F.Paste")
			(net "GND")
		)
		(pad "267" smd rect
			(at 2.050034 45.47489 90)
			(size 0.519938 1.4986)
			(layers "F.Cu" "F.Mask" "F.Paste")
			(net "M_A_CPU1_SB_DQ<18>")
		)
		(pad "268" smd rect
			(at 2.050034 46.325028 90)
			(size 0.519938 1.4986)
			(layers "F.Cu" "F.Mask" "F.Paste")
			(net "GND")
		)
		(pad "269" smd rect
			(at 2.050034 47.174912 90)
			(size 0.519938 1.4986)
			(layers "F.Cu" "F.Mask" "F.Paste")
			(net "M_A_CPU1_SB_DQ<19>")
		)
		(pad "270" smd rect
			(at 2.050034 48.02505 90)
			(size 0.519938 1.4986)
			(layers "F.Cu" "F.Mask" "F.Paste")
			(net "GND")
		)
		(pad "271" smd rect
			(at 2.050034 48.874934 90)
			(size 0.519938 1.4986)
			(layers "F.Cu" "F.Mask" "F.Paste")
			(net "M_A_CPU1_SB_DQS_DN<7>")
		)
		(pad "272" smd rect
			(at 2.050034 49.725072 90)
			(size 0.519938 1.4986)
			(layers "F.Cu" "F.Mask" "F.Paste")
			(net "M_A_CPU1_SB_DQS_DP<7>")
		)
		(pad "273" smd rect
			(at 2.050034 50.574956 90)
			(size 0.519938 1.4986)
			(layers "F.Cu" "F.Mask" "F.Paste")
			(net "GND")
		)
		(pad "274" smd rect
			(at 2.050034 51.425094 90)
			(size 0.519938 1.4986)
			(layers "F.Cu" "F.Mask" "F.Paste")
			(net "M_A_CPU1_SB_DQ<22>")
		)
		(pad "275" smd rect
			(at 2.050034 52.274978 90)
			(size 0.519938 1.4986)
			(layers "F.Cu" "F.Mask" "F.Paste")
			(net "GND")
		)
		(pad "276" smd rect
			(at 2.050034 53.125116 90)
			(size 0.519938 1.4986)
			(layers "F.Cu" "F.Mask" "F.Paste")
			(net "M_A_CPU1_SB_DQ<23>")
		)
	)
)
